# BASEBOARD_FAB2 (Tioga Pass) — schematic netlist excerpt (pin names and nets, part order shuffled) for the footprints in the layout excerpt that follows; sources: Cadence DE-HDL packaged netlist, KiCad conversion of Wiwynn_Tioga_Pass_MB.brd

R7W11  RES  0.0 5% CHIP  pkg 0402  page 120 : A = FM_CPU1_RC_ERROR_R_N ; B = FM_CPU1_RC_ERROR_N
C8E10  CAP  22UF 16V 10% X6S  pkg 1206LF  page 240 : A = VR_FET_SW_P12V_STBY_P3V3_STBY ; B = GND
R2U41  RES  150.0 1% CHIP  pkg 0402  page 152 : A = PVCCIO_CPU0 ; B = H_CPU0_MEMDEF_MEMHOT_G_N

(kicad_pcb
	(version 20260206)
	(generator "pcbnew")
	(generator_version "10.0")
	(general
		(thickness 1.6)
		(legacy_teardrops no)
	)
	(paper "A4")
	(title_block
		(title "Wiwynn_Tioga_Pass_MB.brd")
		(comment 1 "Tioga Pass / footprints 1193-1195 of 4770")
	)
	(layers
		(0 "F.Cu" signal "TOP")
		(4 "In1.Cu" signal "L2GND")
		(6 "In2.Cu" signal "L3")
		(8 "In3.Cu" signal "L4GND")
		(10 "In4.Cu" signal "L5")
		(12 "In5.Cu" signal "L6GND")
		(14 "In6.Cu" signal "L7VCC")
		(16 "In7.Cu" signal "L8VCC")
		(18 "In8.Cu" signal "L9GND")
		(20 "In9.Cu" signal "L10")
		(22 "In10.Cu" signal "L11GND")
		(24 "In11.Cu" signal "L12")
		(26 "In12.Cu" signal "L13GND")
		(2 "B.Cu" signal "BOTTOM")
		(9 "F.Adhes" user "F.Adhesive")
		(11 "B.Adhes" user "B.Adhesive")
		(13 "F.Paste" user "Package Geometry/Pastemask Top")
		(15 "B.Paste" user "Package Geometry/Pastemask Bottom")
		(5 "F.SilkS" user "Ref Des/Silkscreen Top")
		(7 "B.SilkS" user "Ref Des/Silkscreen Bottom")
		(1 "F.Mask" user "Board Geometry/Soldermask Top")
		(3 "B.Mask" user "Board Geometry/Soldermask Bottom")
		(17 "Dwgs.User" user "User.Drawings")
		(19 "Cmts.User" user "User.Comments")
		(21 "Eco1.User" user "User.Eco1")
		(23 "Eco2.User" user "User.Eco2")
		(25 "Edge.Cuts" user "Board Geometry/Outline")
		(27 "Margin" user)
		(31 "F.CrtYd" user "Package Geometry/Place Bound Top")
		(29 "B.CrtYd" user "Package Geometry/Place Bound Bottom")
		(35 "F.Fab" user "Ref Des/Assembly Top")
		(33 "B.Fab" user "Ref Des/Assembly Bottom")
	)
	(footprint ""
		(layer "F.Cu")
		(at 439.293 -12.954 180)
		(property "Reference" "R2U41"
			(at 0 0 180)
			(layer "F.SilkS")
			(hide yes)
			(effects
				(font
					(size 1.27 1.27)
				)
			)
		)
		(property "Value" ""
			(at 0 0 180)
			(layer "F.Fab")
			(effects
				(font
					(size 1.27 1.27)
				)
			)
		)
		(duplicate_pad_numbers_are_jumpers no)
		(fp_poly
			(pts
				(xy -0.2794 -0.1016) (xy 0.2794 -0.1016) (xy 0.2794 0.9906) (xy -0.2794 0.9906)
			)
			(stroke
				(width 0)
				(type default)
			)
			(fill no)
			(layer "F.CrtYd")
		)
		(fp_line
			(start 0.2794 0.9906)
			(end 0.2794 -0.1016)
			(stroke
				(width 0.1)
				(type default)
			)
			(layer "F.Fab")
		)
		(fp_line
			(start 0.2794 -0.1016)
			(end -0.2794 -0.1016)
			(stroke
				(width 0.1)
				(type default)
			)
			(layer "F.Fab")
		)
		(fp_line
			(start -0.2794 0.9906)
			(end 0.2794 0.9906)
			(stroke
				(width 0.1)
				(type default)
			)
			(layer "F.Fab")
		)
		(fp_line
			(start -0.2794 -0.1016)
			(end -0.2794 0.9906)
			(stroke
				(width 0.1)
				(type default)
			)
			(layer "F.Fab")
		)
		(pad "1" smd rect
			(at 0 0 180)
			(size 0.508 0.508)
			(layers "F.Cu" "F.Mask" "F.Paste")
			(net "PVCCIO_CPU0")
		)
		(pad "2" smd rect
			(at 0 0.889 180)
			(size 0.508 0.508)
			(layers "F.Cu" "F.Mask" "F.Paste")
			(net "H_CPU0_MEMDEF_MEMHOT_G_N")
		)
		(zone
			(layer "F.Cu")
			(hatch none 0.5)
			(connect_pads
				(clearance 0)
			)
			(min_thickness 0.25)
			(keepout
				(tracks not_allowed)
				(vias allowed)
				(pads allowed)
				(copperpour not_allowed)
				(footprints allowed)
			)
			(placement
				(enabled no)
				(sheetname "")
			)
			(fill
				(thermal_gap 0.5)
				(thermal_bridge_width 0.5)
				(island_removal_mode 0)
			)
			(polygon
				(pts
					(xy 439.547 -13.589) (xy 439.039 -13.589) (xy 439.039 -13.208) (xy 439.547 -13.208)
				)
			)
		)
		(zone
			(layer "F.Cu")
			(hatch none 0.5)
			(connect_pads
				(clearance 0)
			)
			(min_thickness 0.25)
			(keepout
				(tracks allowed)
				(vias not_allowed)
				(pads allowed)
				(copperpour not_allowed)
				(footprints allowed)
			)
			(placement
				(enabled no)
				(sheetname "")
			)
			(fill
				(thermal_gap 0.5)
				(thermal_bridge_width 0.5)
				(island_removal_mode 0)
			)
			(polygon
				(pts
					(xy 439.547 -13.208) (xy 439.039 -13.208) (xy 439.039 -13.589) (xy 439.547 -13.589)
				)
			)
		)
	)
	(footprint ""
		(layer "F.Cu")
		(at 410.6926 -103.3526)
		(property "Reference" "R7W11"
			(at -0.8382 -0.67818 0)
			(unlocked yes)
			(layer "F.SilkS")
			(effects
				(font
					(size 0.4064 0.254)
					(thickness 0.1524)
				)
				(justify left)
			)
		)
		(property "Value" ""
			(at 0 0 0)
			(layer "F.Fab")
			(effects
				(font
					(size 1.27 1.27)
				)
			)
		)
		(duplicate_pad_numbers_are_jumpers no)
		(fp_poly
			(pts
				(xy -0.2794 -0.1016) (xy 0.2794 -0.1016) (xy 0.2794 0.9906) (xy -0.2794 0.9906)
			)
			(stroke
				(width 0)
				(type default)
			)
			(fill no)
			(layer "F.CrtYd")
		)
		(fp_line
			(start -0.2794 -0.1016)
			(end -0.2794 0.9906)
			(stroke
				(width 0.1)
				(type default)
			)
			(layer "F.Fab")
		)
		(fp_line
			(start -0.2794 0.9906)
			(end 0.2794 0.9906)
			(stroke
				(width 0.1)
				(type default)
			)
			(layer "F.Fab")
		)
		(fp_line
			(start 0.2794 -0.1016)
			(end -0.2794 -0.1016)
			(stroke
				(width 0.1)
				(type default)
			)
			(layer "F.Fab")
		)
		(fp_line
			(start 0.2794 0.9906)
			(end 0.2794 -0.1016)
			(stroke
				(width 0.1)
				(type default)
			)
			(layer "F.Fab")
		)
		(pad "1" smd rect
			(at 0 0)
			(size 0.508 0.508)
			(layers "F.Cu" "F.Mask" "F.Paste")
			(net "FM_CPU1_RC_ERROR_R_N")
		)
		(pad "2" smd rect
			(at 0 0.889)
			(size 0.508 0.508)
			(layers "F.Cu" "F.Mask" "F.Paste")
			(net "FM_CPU1_RC_ERROR_N")
		)
		(zone
			(layer "F.Cu")
			(hatch none 0.5)
			(connect_pads
				(clearance 0)
			)
			(min_thickness 0.25)
			(keepout
				(tracks allowed)
				(vias not_allowed)
				(pads allowed)
				(copperpour not_allowed)
				(footprints allowed)
			)
			(placement
				(enabled no)
				(sheetname "")
			)
			(fill
				(thermal_gap 0.5)
				(thermal_bridge_width 0.5)
				(island_removal_mode 0)
			)
			(polygon
				(pts
					(xy 410.4386 -103.0986) (xy 410.9466 -103.0986) (xy 410.9466 -102.7176) (xy 410.4386 -102.7176)
				)
			)
		)
		(zone
			(layer "F.Cu")
			(hatch none 0.5)
			(connect_pads
				(clearance 0)
			)
			(min_thickness 0.25)
			(keepout
				(tracks not_allowed)
				(vias allowed)
				(pads allowed)
				(copperpour not_allowed)
				(footprints allowed)
			)
			(placement
				(enabled no)
				(sheetname "")
			)
			(fill
				(thermal_gap 0.5)
				(thermal_bridge_width 0.5)
				(island_removal_mode 0)
			)
			(polygon
				(pts
					(xy 410.4386 -102.7176) (xy 410.9466 -102.7176) (xy 410.9466 -103.0986) (xy 410.4386 -103.0986)
				)
			)
		)
	)
	(footprint ""
		(layer "F.Cu")
		(at 479.9076 -22.4282)
		(property "Reference" "C8E10"
			(at -0.381 -1.21793 0)
			(unlocked yes)
			(layer "F.SilkS")
			(effects
				(font
					(size 0.7874 0.5842)
					(thickness 0.1524)
				)
			)
		)
		(property "Value" ""
			(at 0 0 0)
			(layer "F.Fab")
			(effects
				(font
					(size 1.27 1.27)
				)
			)
		)
		(duplicate_pad_numbers_are_jumpers no)
		(fp_line
			(start -0.9017 1.953006)
			(end -0.9017 0.823976)
			(stroke
				(width 0.1524)
				(type default)
			)
			(layer "F.SilkS")
		)
		(fp_line
			(start 0.9017 1.953768)
			(end 0.9017 0.824484)
			(stroke
				(width 0.1524)
				(type default)
			)
			(layer "F.SilkS")
		)
		(fp_poly
			(pts
				(xy -0.9017 -0.3048) (xy 0.9017 -0.3048) (xy 0.9017 3.0988) (xy -0.9017 3.0988)
			)
			(stroke
				(width 0)
				(type default)
			)
			(fill no)
			(layer "F.CrtYd")
		)
		(fp_line
			(start -0.9017 -0.3048)
			(end -0.9017 3.0988)
			(stroke
				(width 0.1)
				(type default)
			)
			(layer "F.Fab")
		)
		(fp_line
			(start -0.9017 3.0988)
			(end 0.9017 3.0988)
			(stroke
				(width 0.1)
				(type default)
			)
			(layer "F.Fab")
		)
		(fp_line
			(start 0.9017 -0.3048)
			(end -0.9017 -0.3048)
			(stroke
				(width 0.1)
				(type default)
			)
			(layer "F.Fab")
		)
		(fp_line
			(start 0.9017 3.0988)
			(end 0.9017 -0.3048)
			(stroke
				(width 0.1)
				(type default)
			)
			(layer "F.Fab")
		)
		(pad "1" smd rect
			(at 0 0)
			(size 1.524 1.016)
			(layers "F.Cu" "F.Mask" "F.Paste")
			(net "VR_FET_SW_P12V_STBY_P3V3_STBY")
		)
		(pad "2" smd rect
			(at 0 2.794)
			(size 1.524 1.016)
			(layers "F.Cu" "F.Mask" "F.Paste")
			(net "GND")
		)
		(zone
			(layer "F.Cu")
			(hatch none 0.5)
			(connect_pads
				(clearance 0)
			)
			(min_thickness 0.25)
			(keepout
				(tracks allowed)
				(vias not_allowed)
				(pads allowed)
				(copperpour not_allowed)
				(footprints allowed)
			)
			(placement
				(enabled no)
				(sheetname "")
			)
			(fill
				(thermal_gap 0.5)
				(thermal_bridge_width 0.5)
				(island_removal_mode 0)
			)
			(polygon
				(pts
					(xy 480.6696 -21.9202) (xy 480.6696 -20.1422) (xy 479.1456 -20.1422) (xy 479.1456 -21.9202)
				)
			)
		)
	)
)
